(kicad_pcb
	(version 20260206)
	(generator "pcbnew")
	(generator_version "10.0")
	(general
		(thickness 1.6)
		(legacy_teardrops no)
	)
	(paper "A4")
	(title_block
		(title "01162023_DA0F0TEBIF0_F0T_Expander_BD_F_brd_V02_OCP.brd")
		(comment 1 "Grand Teton / footprints 6403-6409 of 9728")
	)
	(layers
		(0 "F.Cu" signal "TOP")
		(4 "In1.Cu" signal "GND")
		(6 "In2.Cu" signal "VCC")
		(8 "In3.Cu" signal "VCC1")
		(10 "In4.Cu" signal "GND1")
		(12 "In5.Cu" signal "IN1")
		(14 "In6.Cu" signal "GND2")
		(16 "In7.Cu" signal "IN2")
		(18 "In8.Cu" signal "GND3")
		(20 "In9.Cu" signal "IN3")
		(22 "In10.Cu" signal "GND4")
		(24 "In11.Cu" signal "IN4")
		(26 "In12.Cu" signal "GND5")
		(28 "In13.Cu" signal "IN5")
		(30 "In14.Cu" signal "GND6")
		(32 "In15.Cu" signal "IN6")
		(34 "In16.Cu" signal "GND7")
		(2 "B.Cu" signal "BOTTOM")
		(9 "F.Adhes" user "F.Adhesive")
		(11 "B.Adhes" user "B.Adhesive")
		(13 "F.Paste" user "Package Geometry/Pastemask Top")
		(15 "B.Paste" user "Package Geometry/Pastemask Bottom")
		(5 "F.SilkS" user "Ref Des/Silkscreen Top")
		(7 "B.SilkS" user "Ref Des/Silkscreen Bottom")
		(1 "F.Mask" user "Board Geometry/Soldermask Top")
		(3 "B.Mask" user "Board Geometry/Soldermask Bottom")
		(17 "Dwgs.User" user "User.Drawings")
		(19 "Cmts.User" user "User.Comments")
		(21 "Eco1.User" user "User.Eco1")
		(23 "Eco2.User" user "User.Eco2")
		(25 "Edge.Cuts" user "Board Geometry/Outline")
		(27 "Margin" user)
		(31 "F.CrtYd" user "Package Geometry/Place Bound Top")
		(29 "B.CrtYd" user "Package Geometry/Place Bound Bottom")
		(35 "F.Fab" user "Ref Des/Assembly Top")
		(33 "B.Fab" user "Ref Des/Assembly Bottom")
	)
	(footprint ""
		(layer "F.Cu")
		(at 224.022158 -87.716868)
		(property "Reference" "R4263"
			(at 0 0 0)
			(layer "F.SilkS")
			(hide yes)
			(effects
				(font
					(size 1.27 1.27)
				)
			)
		)
		(property "Value" ""
			(at 0 0 0)
			(layer "F.Fab")
			(effects
				(font
					(size 1.27 1.27)
				)
			)
		)
		(duplicate_pad_numbers_are_jumpers no)
		(fp_line
			(start -0.7874 -0.4064)
			(end 0.7874 -0.4064)
			(stroke
				(width 0.1524)
				(type default)
			)
			(layer "F.SilkS")
		)
		(fp_line
			(start -0.7874 0.4064)
			(end -0.7874 -0.4064)
			(stroke
				(width 0.1524)
				(type default)
			)
			(layer "F.SilkS")
		)
		(fp_line
			(start 0.7874 -0.4064)
			(end 0.7874 0.4064)
			(stroke
				(width 0.1524)
				(type default)
			)
			(layer "F.SilkS")
		)
		(fp_line
			(start 0.7874 0.4064)
			(end -0.7874 0.4064)
			(stroke
				(width 0.1524)
				(type default)
			)
			(layer "F.SilkS")
		)
		(fp_line
			(start -0.67945 -0.305054)
			(end -0.12065 -0.305054)
			(stroke
				(width 0.1)
				(type default)
			)
			(layer "F.Fab")
		)
		(fp_line
			(start -0.67945 0.3048)
			(end -0.67945 -0.305054)
			(stroke
				(width 0.1)
				(type default)
			)
			(layer "F.Fab")
		)
		(fp_line
			(start -0.12065 -0.305054)
			(end -0.12065 -0.2794)
			(stroke
				(width 0.1)
				(type default)
			)
			(layer "F.Fab")
		)
		(fp_line
			(start -0.12065 -0.2794)
			(end 0.12065 -0.2794)
			(stroke
				(width 0.1)
				(type default)
			)
			(layer "F.Fab")
		)
		(fp_line
			(start -0.12065 0.2794)
			(end -0.12065 0.3048)
			(stroke
				(width 0.1)
				(type default)
			)
			(layer "F.Fab")
		)
		(fp_line
			(start -0.12065 0.3048)
			(end -0.67945 0.3048)
			(stroke
				(width 0.1)
				(type default)
			)
			(layer "F.Fab")
		)
		(fp_line
			(start 0.120396 0.2794)
			(end -0.12065 0.2794)
			(stroke
				(width 0.1)
				(type default)
			)
			(layer "F.Fab")
		)
		(fp_line
			(start 0.120396 0.3048)
			(end 0.120396 0.2794)
			(stroke
				(width 0.1)
				(type default)
			)
			(layer "F.Fab")
		)
		(fp_line
			(start 0.12065 -0.3048)
			(end 0.67945 -0.3048)
			(stroke
				(width 0.1)
				(type default)
			)
			(layer "F.Fab")
		)
		(fp_line
			(start 0.12065 -0.2794)
			(end 0.12065 -0.3048)
			(stroke
				(width 0.1)
				(type default)
			)
			(layer "F.Fab")
		)
		(fp_line
			(start 0.67945 -0.3048)
			(end 0.67945 0.3048)
			(stroke
				(width 0.1)
				(type default)
			)
			(layer "F.Fab")
		)
		(fp_line
			(start 0.67945 0.3048)
			(end 0.120396 0.3048)
			(stroke
				(width 0.1)
				(type default)
			)
			(layer "F.Fab")
		)
		(pad "1" smd circle
			(at -0.40005 0)
			(size 0 0)
			(layers "F.Cu" "F.Mask" "F.Paste")
			(net "SMB_SSD_LED_IOEXP_SDA")
		)
		(pad "2" smd circle
			(at 0.40005 0)
			(size 0 0)
			(layers "F.Cu" "F.Mask" "F.Paste")
			(net "SMB_BIC_I2C6_R_SDA")
		)
	)
	(footprint ""
		(layer "F.Cu")
		(at 139.817348 -356.244906 90)
		(property "Reference" "C2261"
			(at 0 0 90)
			(layer "F.SilkS")
			(hide yes)
			(effects
				(font
					(size 1.27 1.27)
				)
			)
		)
		(property "Value" ""
			(at 0 0 90)
			(layer "F.Fab")
			(effects
				(font
					(size 1.27 1.27)
				)
			)
		)
		(duplicate_pad_numbers_are_jumpers no)
		(fp_line
			(start 0.299974 -0.150114)
			(end 0.299974 0.150114)
			(stroke
				(width 0.1)
				(type default)
			)
			(layer "F.Fab")
		)
		(fp_line
			(start -0.299974 -0.150114)
			(end 0.299974 -0.150114)
			(stroke
				(width 0.1)
				(type default)
			)
			(layer "F.Fab")
		)
		(fp_line
			(start 0.299974 0.150114)
			(end -0.299974 0.150114)
			(stroke
				(width 0.1)
				(type default)
			)
			(layer "F.Fab")
		)
		(fp_line
			(start -0.299974 0.150114)
			(end -0.299974 -0.150114)
			(stroke
				(width 0.1)
				(type default)
			)
			(layer "F.Fab")
		)
		(pad "1" smd rect
			(at -0.2667 0 90)
			(size 0.3048 0.381)
			(layers "F.Cu" "F.Mask" "F.Paste")
			(net "P5E_PEX1_STN5_TX_DP<86>")
		)
		(pad "2" smd rect
			(at 0.2667 0 90)
			(size 0.3048 0.381)
			(layers "F.Cu" "F.Mask" "F.Paste")
			(net "P5E_PEX1_STN5_TX_C_DP<86>")
		)
	)
	(footprint ""
		(layer "F.Cu")
		(at 379.998732 -309.570628 45)
		(property "Reference" "R1420"
			(at 0 0 45)
			(layer "F.SilkS")
			(hide yes)
			(effects
				(font
					(size 1.27 1.27)
				)
			)
		)
		(property "Value" ""
			(at 0 0 45)
			(layer "F.Fab")
			(effects
				(font
					(size 1.27 1.27)
				)
			)
		)
		(duplicate_pad_numbers_are_jumpers no)
		(fp_line
			(start -0.787389 -0.406267)
			(end 0.787389 -0.406267)
			(stroke
				(width 0.1524)
				(type default)
			)
			(layer "F.SilkS")
		)
		(fp_line
			(start -0.787389 0.406267)
			(end -0.787389 -0.406267)
			(stroke
				(width 0.1524)
				(type default)
			)
			(layer "F.SilkS")
		)
		(fp_line
			(start 0.787389 -0.406267)
			(end 0.787389 0.406267)
			(stroke
				(width 0.1524)
				(type default)
			)
			(layer "F.SilkS")
		)
		(fp_line
			(start 0.787389 0.406267)
			(end -0.787389 0.406267)
			(stroke
				(width 0.1524)
				(type default)
			)
			(layer "F.SilkS")
		)
		(fp_line
			(start -0.679446 -0.305149)
			(end -0.120695 -0.304969)
			(stroke
				(width 0.1)
				(type default)
			)
			(layer "F.Fab")
		)
		(fp_line
			(start -0.120695 -0.304969)
			(end -0.120695 -0.279466)
			(stroke
				(width 0.1)
				(type default)
			)
			(layer "F.Fab")
		)
		(fp_line
			(start -0.120695 -0.279466)
			(end 0.120695 -0.279466)
			(stroke
				(width 0.1)
				(type default)
			)
			(layer "F.Fab")
		)
		(fp_line
			(start -0.679446 0.30479)
			(end -0.679446 -0.305149)
			(stroke
				(width 0.1)
				(type default)
			)
			(layer "F.Fab")
		)
		(fp_line
			(start 0.120515 -0.30479)
			(end 0.679446 -0.30479)
			(stroke
				(width 0.1)
				(type default)
			)
			(layer "F.Fab")
		)
		(fp_line
			(start 0.120695 -0.279466)
			(end 0.120515 -0.30479)
			(stroke
				(width 0.1)
				(type default)
			)
			(layer "F.Fab")
		)
		(fp_line
			(start -0.120695 0.279466)
			(end -0.120515 0.30479)
			(stroke
				(width 0.1)
				(type default)
			)
			(layer "F.Fab")
		)
		(fp_line
			(start -0.120515 0.30479)
			(end -0.679446 0.30479)
			(stroke
				(width 0.1)
				(type default)
			)
			(layer "F.Fab")
		)
		(fp_line
			(start 0.679446 -0.30479)
			(end 0.679446 0.30479)
			(stroke
				(width 0.1)
				(type default)
			)
			(layer "F.Fab")
		)
		(fp_line
			(start 0.120335 0.279466)
			(end -0.120695 0.279466)
			(stroke
				(width 0.1)
				(type default)
			)
			(layer "F.Fab")
		)
		(fp_line
			(start 0.120515 0.30479)
			(end 0.120335 0.279466)
			(stroke
				(width 0.1)
				(type default)
			)
			(layer "F.Fab")
		)
		(fp_line
			(start 0.679446 0.30479)
			(end 0.120515 0.30479)
			(stroke
				(width 0.1)
				(type default)
			)
			(layer "F.Fab")
		)
		(pad "1" smd circle
			(at -0.40005 0 45)
			(size 0 0)
			(layers "F.Cu" "F.Mask" "F.Paste")
			(net "GND")
		)
		(pad "2" smd circle
			(at 0.40005 0 45)
			(size 0 0)
			(layers "F.Cu" "F.Mask" "F.Paste")
			(net "PEX3_DBG_MODE0")
		)
	)
	(footprint ""
		(layer "F.Cu")
		(at 175.0949 -100.766372 180)
		(property "Reference" "R180"
			(at 0 0 180)
			(layer "F.SilkS")
			(hide yes)
			(effects
				(font
					(size 1.27 1.27)
				)
			)
		)
		(property "Value" ""
			(at 0 0 180)
			(layer "F.Fab")
			(effects
				(font
					(size 1.27 1.27)
				)
			)
		)
		(duplicate_pad_numbers_are_jumpers no)
		(fp_line
			(start 0.7874 0.4064)
			(end -0.7874 0.4064)
			(stroke
				(width 0.1524)
				(type default)
			)
			(layer "F.SilkS")
		)
		(fp_line
			(start 0.7874 -0.4064)
			(end 0.7874 0.4064)
			(stroke
				(width 0.1524)
				(type default)
			)
			(layer "F.SilkS")
		)
		(fp_line
			(start -0.7874 0.4064)
			(end -0.7874 -0.4064)
			(stroke
				(width 0.1524)
				(type default)
			)
			(layer "F.SilkS")
		)
		(fp_line
			(start -0.7874 -0.4064)
			(end 0.7874 -0.4064)
			(stroke
				(width 0.1524)
				(type default)
			)
			(layer "F.SilkS")
		)
		(fp_line
			(start 0.67945 0.3048)
			(end 0.120396 0.3048)
			(stroke
				(width 0.1)
				(type default)
			)
			(layer "F.Fab")
		)
		(fp_line
			(start 0.67945 -0.3048)
			(end 0.67945 0.3048)
			(stroke
				(width 0.1)
				(type default)
			)
			(layer "F.Fab")
		)
		(fp_line
			(start 0.12065 -0.2794)
			(end 0.12065 -0.3048)
			(stroke
				(width 0.1)
				(type default)
			)
			(layer "F.Fab")
		)
		(fp_line
			(start 0.12065 -0.3048)
			(end 0.67945 -0.3048)
			(stroke
				(width 0.1)
				(type default)
			)
			(layer "F.Fab")
		)
		(fp_line
			(start 0.120396 0.3048)
			(end 0.120396 0.2794)
			(stroke
				(width 0.1)
				(type default)
			)
			(layer "F.Fab")
		)
		(fp_line
			(start 0.120396 0.2794)
			(end -0.12065 0.2794)
			(stroke
				(width 0.1)
				(type default)
			)
			(layer "F.Fab")
		)
		(fp_line
			(start -0.12065 0.3048)
			(end -0.67945 0.3048)
			(stroke
				(width 0.1)
				(type default)
			)
			(layer "F.Fab")
		)
		(fp_line
			(start -0.12065 0.2794)
			(end -0.12065 0.3048)
			(stroke
				(width 0.1)
				(type default)
			)
			(layer "F.Fab")
		)
		(fp_line
			(start -0.12065 -0.2794)
			(end 0.12065 -0.2794)
			(stroke
				(width 0.1)
				(type default)
			)
			(layer "F.Fab")
		)
		(fp_line
			(start -0.12065 -0.305054)
			(end -0.12065 -0.2794)
			(stroke
				(width 0.1)
				(type default)
			)
			(layer "F.Fab")
		)
		(fp_line
			(start -0.67945 0.3048)
			(end -0.67945 -0.305054)
			(stroke
				(width 0.1)
				(type default)
			)
			(layer "F.Fab")
		)
		(fp_line
			(start -0.67945 -0.305054)
			(end -0.12065 -0.305054)
			(stroke
				(width 0.1)
				(type default)
			)
			(layer "F.Fab")
		)
		(pad "1" smd circle
			(at -0.40005 0 180)
			(size 0 0)
			(layers "F.Cu" "F.Mask" "F.Paste")
			(net "NIC3_SLOT_ID1")
		)
		(pad "2" smd circle
			(at 0.40005 0 180)
			(size 0 0)
			(layers "F.Cu" "F.Mask" "F.Paste")
			(net "P3V3_NIC3")
		)
	)
	(footprint ""
		(layer "F.Cu")
		(at 284.443678 -49.95291 180)
		(property "Reference" "R610"
			(at 0 0 180)
			(layer "F.SilkS")
			(hide yes)
			(effects
				(font
					(size 1.27 1.27)
				)
			)
		)
		(property "Value" ""
			(at 0 0 180)
			(layer "F.Fab")
			(effects
				(font
					(size 1.27 1.27)
				)
			)
		)
		(duplicate_pad_numbers_are_jumpers no)
		(fp_line
			(start 0.7874 0.4064)
			(end -0.7874 0.4064)
			(stroke
				(width 0.1524)
				(type default)
			)
			(layer "F.SilkS")
		)
		(fp_line
			(start 0.7874 -0.4064)
			(end 0.7874 0.4064)
			(stroke
				(width 0.1524)
				(type default)
			)
			(layer "F.SilkS")
		)
		(fp_line
			(start -0.7874 0.4064)
			(end -0.7874 -0.4064)
			(stroke
				(width 0.1524)
				(type default)
			)
			(layer "F.SilkS")
		)
		(fp_line
			(start -0.7874 -0.4064)
			(end 0.7874 -0.4064)
			(stroke
				(width 0.1524)
				(type default)
			)
			(layer "F.SilkS")
		)
		(fp_line
			(start 0.67945 0.3048)
			(end 0.120396 0.3048)
			(stroke
				(width 0.1)
				(type default)
			)
			(layer "F.Fab")
		)
		(fp_line
			(start 0.67945 -0.3048)
			(end 0.67945 0.3048)
			(stroke
				(width 0.1)
				(type default)
			)
			(layer "F.Fab")
		)
		(fp_line
			(start 0.12065 -0.2794)
			(end 0.12065 -0.3048)
			(stroke
				(width 0.1)
				(type default)
			)
			(layer "F.Fab")
		)
		(fp_line
			(start 0.12065 -0.3048)
			(end 0.67945 -0.3048)
			(stroke
				(width 0.1)
				(type default)
			)
			(layer "F.Fab")
		)
		(fp_line
			(start 0.120396 0.3048)
			(end 0.120396 0.2794)
			(stroke
				(width 0.1)
				(type default)
			)
			(layer "F.Fab")
		)
		(fp_line
			(start 0.120396 0.2794)
			(end -0.12065 0.2794)
			(stroke
				(width 0.1)
				(type default)
			)
			(layer "F.Fab")
		)
		(fp_line
			(start -0.12065 0.3048)
			(end -0.67945 0.3048)
			(stroke
				(width 0.1)
				(type default)
			)
			(layer "F.Fab")
		)
		(fp_line
			(start -0.12065 0.2794)
			(end -0.12065 0.3048)
			(stroke
				(width 0.1)
				(type default)
			)
			(layer "F.Fab")
		)
		(fp_line
			(start -0.12065 -0.2794)
			(end 0.12065 -0.2794)
			(stroke
				(width 0.1)
				(type default)
			)
			(layer "F.Fab")
		)
		(fp_line
			(start -0.12065 -0.305054)
			(end -0.12065 -0.2794)
			(stroke
				(width 0.1)
				(type default)
			)
			(layer "F.Fab")
		)
		(fp_line
			(start -0.67945 0.3048)
			(end -0.67945 -0.305054)
			(stroke
				(width 0.1)
				(type default)
			)
			(layer "F.Fab")
		)
		(fp_line
			(start -0.67945 -0.305054)
			(end -0.12065 -0.305054)
			(stroke
				(width 0.1)
				(type default)
			)
			(layer "F.Fab")
		)
		(pad "1" smd circle
			(at -0.40005 0 180)
			(size 0 0)
			(layers "F.Cu" "F.Mask" "F.Paste")
			(net "SMB_BIC_I2C6_MUX_SSD_8_15_ADC_R_SCL")
		)
		(pad "2" smd circle
			(at 0.40005 0 180)
			(size 0 0)
			(layers "F.Cu" "F.Mask" "F.Paste")
			(net "SMB_SSD9_ADC_SCL")
		)
	)
	(footprint ""
		(layer "F.Cu")
		(at 361.048808 -162.003994 90)
		(property "Reference" "PR7056"
			(at 0 0 90)
			(layer "F.SilkS")
			(hide yes)
			(effects
				(font
					(size 1.27 1.27)
				)
			)
		)
		(property "Value" ""
			(at 0 0 90)
			(layer "F.Fab")
			(effects
				(font
					(size 1.27 1.27)
				)
			)
		)
		(duplicate_pad_numbers_are_jumpers no)
		(fp_line
			(start 0.7874 -0.4064)
			(end 0.7874 0.4064)
			(stroke
				(width 0.1524)
				(type default)
			)
			(layer "F.SilkS")
		)
		(fp_line
			(start -0.7874 -0.4064)
			(end 0.7874 -0.4064)
			(stroke
				(width 0.1524)
				(type default)
			)
			(layer "F.SilkS")
		)
		(fp_line
			(start 0.7874 0.4064)
			(end -0.7874 0.4064)
			(stroke
				(width 0.1524)
				(type default)
			)
			(layer "F.SilkS")
		)
		(fp_line
			(start -0.7874 0.4064)
			(end -0.7874 -0.4064)
			(stroke
				(width 0.1524)
				(type default)
			)
			(layer "F.SilkS")
		)
		(fp_line
			(start -0.12065 -0.305054)
			(end -0.12065 -0.2794)
			(stroke
				(width 0.1)
				(type default)
			)
			(layer "F.Fab")
		)
		(fp_line
			(start -0.67945 -0.305054)
			(end -0.12065 -0.305054)
			(stroke
				(width 0.1)
				(type default)
			)
			(layer "F.Fab")
		)
		(fp_line
			(start 0.67945 -0.3048)
			(end 0.67945 0.3048)
			(stroke
				(width 0.1)
				(type default)
			)
			(layer "F.Fab")
		)
		(fp_line
			(start 0.12065 -0.3048)
			(end 0.67945 -0.3048)
			(stroke
				(width 0.1)
				(type default)
			)
			(layer "F.Fab")
		)
		(fp_line
			(start 0.12065 -0.2794)
			(end 0.12065 -0.3048)
			(stroke
				(width 0.1)
				(type default)
			)
			(layer "F.Fab")
		)
		(fp_line
			(start -0.12065 -0.2794)
			(end 0.12065 -0.2794)
			(stroke
				(width 0.1)
				(type default)
			)
			(layer "F.Fab")
		)
		(fp_line
			(start 0.120396 0.2794)
			(end -0.12065 0.2794)
			(stroke
				(width 0.1)
				(type default)
			)
			(layer "F.Fab")
		)
		(fp_line
			(start -0.12065 0.2794)
			(end -0.12065 0.3048)
			(stroke
				(width 0.1)
				(type default)
			)
			(layer "F.Fab")
		)
		(fp_line
			(start 0.67945 0.3048)
			(end 0.120396 0.3048)
			(stroke
				(width 0.1)
				(type default)
			)
			(layer "F.Fab")
		)
		(fp_line
			(start 0.120396 0.3048)
			(end 0.120396 0.2794)
			(stroke
				(width 0.1)
				(type default)
			)
			(layer "F.Fab")
		)
		(fp_line
			(start -0.12065 0.3048)
			(end -0.67945 0.3048)
			(stroke
				(width 0.1)
				(type default)
			)
			(layer "F.Fab")
		)
		(fp_line
			(start -0.67945 0.3048)
			(end -0.67945 -0.305054)
			(stroke
				(width 0.1)
				(type default)
			)
			(layer "F.Fab")
		)
		(pad "1" smd circle
			(at -0.40005 0 90)
			(size 0 0)
			(layers "F.Cu" "F.Mask" "F.Paste")
			(net "P12V_NIC6_CO_ISET")
		)
		(pad "2" smd circle
			(at 0.40005 0 90)
			(size 0 0)
			(layers "F.Cu" "F.Mask" "F.Paste")
			(net "GND")
		)
	)
	(footprint ""
		(layer "F.Cu")
		(at 134.738872 -22.867366 90)
		(property "Reference" "C3903"
			(at 0 0 90)
			(layer "F.SilkS")
			(hide yes)
			(effects
				(font
					(size 1.27 1.27)
				)
			)
		)
		(property "Value" ""
			(at 0 0 90)
			(layer "F.Fab")
			(effects
				(font
					(size 1.27 1.27)
				)
			)
		)
		(duplicate_pad_numbers_are_jumpers no)
		(fp_line
			(start 0.7874 -0.4064)
			(end 0.7874 0.4064)
			(stroke
				(width 0.1524)
				(type default)
			)
			(layer "F.SilkS")
		)
		(fp_line
			(start -0.7874 -0.4064)
			(end 0.7874 -0.4064)
			(stroke
				(width 0.1524)
				(type default)
			)
			(layer "F.SilkS")
		)
		(fp_line
			(start 0.7874 0.4064)
			(end -0.7874 0.4064)
			(stroke
				(width 0.1524)
				(type default)
			)
			(layer "F.SilkS")
		)
		(fp_line
			(start -0.7874 0.4064)
			(end -0.7874 -0.4064)
			(stroke
				(width 0.1524)
				(type default)
			)
			(layer "F.SilkS")
		)
		(fp_line
			(start -0.12065 -0.305054)
			(end -0.12065 -0.2794)
			(stroke
				(width 0.1)
				(type default)
			)
			(layer "F.Fab")
		)
		(fp_line
			(start -0.67945 -0.305054)
			(end -0.12065 -0.305054)
			(stroke
				(width 0.1)
				(type default)
			)
			(layer "F.Fab")
		)
		(fp_line
			(start 0.67945 -0.3048)
			(end 0.67945 0.3048)
			(stroke
				(width 0.1)
				(type default)
			)
			(layer "F.Fab")
		)
		(fp_line
			(start 0.12065 -0.3048)
			(end 0.67945 -0.3048)
			(stroke
				(width 0.1)
				(type default)
			)
			(layer "F.Fab")
		)
		(fp_line
			(start 0.12065 -0.2794)
			(end 0.12065 -0.3048)
			(stroke
				(width 0.1)
				(type default)
			)
			(layer "F.Fab")
		)
		(fp_line
			(start -0.12065 -0.2794)
			(end 0.12065 -0.2794)
			(stroke
				(width 0.1)
				(type default)
			)
			(layer "F.Fab")
		)
		(fp_line
			(start 0.120396 0.2794)
			(end -0.12065 0.2794)
			(stroke
				(width 0.1)
				(type default)
			)
			(layer "F.Fab")
		)
		(fp_line
			(start -0.12065 0.2794)
			(end -0.12065 0.3048)
			(stroke
				(width 0.1)
				(type default)
			)
			(layer "F.Fab")
		)
		(fp_line
			(start 0.67945 0.3048)
			(end 0.120396 0.3048)
			(stroke
				(width 0.1)
				(type default)
			)
			(layer "F.Fab")
		)
		(fp_line
			(start 0.120396 0.3048)
			(end 0.120396 0.2794)
			(stroke
				(width 0.1)
				(type default)
			)
			(layer "F.Fab")
		)
		(fp_line
			(start -0.12065 0.3048)
			(end -0.67945 0.3048)
			(stroke
				(width 0.1)
				(type default)
			)
			(layer "F.Fab")
		)
		(fp_line
			(start -0.67945 0.3048)
			(end -0.67945 -0.305054)
			(stroke
				(width 0.1)
				(type default)
			)
			(layer "F.Fab")
		)
		(pad "1" smd circle
			(at -0.40005 0 90)
			(size 0 0)
			(layers "F.Cu" "F.Mask" "F.Paste")
			(net "P12V_SSD4")
		)
		(pad "2" smd circle
			(at 0.40005 0 90)
			(size 0 0)
			(layers "F.Cu" "F.Mask" "F.Paste")
			(net "GND")
		)
	)
)
